(kicad_pcb
	(version 20260206)
	(generator "pcbnew")
	(generator_version "10.0")
	(general
		(thickness 1.6)
		(legacy_teardrops no)
	)
	(paper "A4")
	(title_block
		(title "v1-chassis-manager — T6M_CM_d_v01_1031_1645.brd")
		(comment 1 "Open CloudServer (Microsoft) / footprints 316-325 of 2512")
	)
	(layers
		(0 "F.Cu" signal "TOP")
		(4 "In1.Cu" signal "GND1")
		(6 "In2.Cu" signal "IN1")
		(8 "In3.Cu" signal "VCC1")
		(10 "In4.Cu" signal "VCC2")
		(12 "In5.Cu" signal "GND2")
		(14 "In6.Cu" signal "IN2")
		(16 "In7.Cu" signal "IN3")
		(18 "In8.Cu" signal "GND3")
		(2 "B.Cu" signal "BOTTOM")
		(9 "F.Adhes" user "F.Adhesive")
		(11 "B.Adhes" user "B.Adhesive")
		(13 "F.Paste" user "Package Geometry/Pastemask Top")
		(15 "B.Paste" user "Package Geometry/Pastemask Bottom")
		(5 "F.SilkS" user "Ref Des/Silkscreen Top")
		(7 "B.SilkS" user "Ref Des/Silkscreen Bottom")
		(1 "F.Mask" user "Board Geometry/Soldermask Top")
		(3 "B.Mask" user "Board Geometry/Soldermask Bottom")
		(17 "Dwgs.User" user "User.Drawings")
		(19 "Cmts.User" user "User.Comments")
		(21 "Eco1.User" user "User.Eco1")
		(23 "Eco2.User" user "User.Eco2")
		(25 "Edge.Cuts" user "Board Geometry/Outline")
		(27 "Margin" user)
		(31 "F.CrtYd" user "Package Geometry/Place Bound Top")
		(29 "B.CrtYd" user "Package Geometry/Place Bound Bottom")
		(35 "F.Fab" user "Ref Des/Assembly Top")
		(33 "B.Fab" user "Ref Des/Assembly Bottom")
	)
	(footprint ""
		(layer "F.Cu")
		(at 112.17021 -153.688034)
		(property "Reference" "R802"
			(at 0 1.257554 0)
			(unlocked yes)
			(layer "F.SilkS")
			(effects
				(font
					(size 0.635 0.4064)
					(thickness 0.1524)
				)
				(justify left)
			)
		)
		(property "Value" ""
			(at 0 0 0)
			(layer "F.Fab")
			(effects
				(font
					(size 1.27 1.27)
				)
			)
		)
		(duplicate_pad_numbers_are_jumpers no)
		(fp_line
			(start -0.7874 -0.4064)
			(end 0.7874 -0.4064)
			(stroke
				(width 0.1524)
				(type default)
			)
			(layer "F.SilkS")
		)
		(fp_line
			(start -0.7874 0.4064)
			(end -0.7874 -0.4064)
			(stroke
				(width 0.1524)
				(type default)
			)
			(layer "F.SilkS")
		)
		(fp_line
			(start 0.7874 -0.4064)
			(end 0.7874 0.4064)
			(stroke
				(width 0.1524)
				(type default)
			)
			(layer "F.SilkS")
		)
		(fp_line
			(start 0.7874 0.4064)
			(end -0.7874 0.4064)
			(stroke
				(width 0.1524)
				(type default)
			)
			(layer "F.SilkS")
		)
		(fp_poly
			(pts
				(xy -0.508 0.2794) (xy -0.508 0.2286) (xy -0.635 0.2286) (xy -0.635 -0.254) (xy -0.5334 -0.254)
				(xy -0.5334 -0.2794) (xy 0.5334 -0.2794) (xy 0.5334 -0.254) (xy 0.635 -0.254) (xy 0.635 0.254) (xy 0.5334 0.254)
				(xy 0.5334 0.2794)
			)
			(stroke
				(width 0)
				(type default)
			)
			(fill no)
			(layer "F.CrtYd")
		)
		(pad "1" smd rect
			(at 0.40005 0)
			(size 0.4572 0.508)
			(layers "F.Cu" "F.Mask" "F.Paste")
			(net "N52410978")
		)
		(pad "2" smd rect
			(at -0.40005 0)
			(size 0.4572 0.508)
			(layers "F.Cu" "F.Mask" "F.Paste")
			(net "P3V3_STB_NODE1")
		)
	)
	(footprint ""
		(layer "F.Cu")
		(at 100.461572 -177.458624 -90)
		(property "Reference" "U67"
			(at 77.037946 -86.148164 0)
			(unlocked yes)
			(layer "F.SilkS")
			(effects
				(font
					(size 0.7874 0.5842)
					(thickness 0.1524)
				)
				(justify left)
			)
		)
		(property "Value" ""
			(at 0 0 270)
			(layer "F.Fab")
			(effects
				(font
					(size 1.27 1.27)
				)
			)
		)
		(duplicate_pad_numbers_are_jumpers no)
		(fp_line
			(start -2.5146 1.4224)
			(end -2.5146 0.4572)
			(stroke
				(width 0.1524)
				(type default)
			)
			(layer "F.SilkS")
		)
		(fp_line
			(start 2.5146 1.4224)
			(end -2.5146 1.4224)
			(stroke
				(width 0.1524)
				(type default)
			)
			(layer "F.SilkS")
		)
		(fp_line
			(start -2.5146 0.4572)
			(end -2.0574 0)
			(stroke
				(width 0.1524)
				(type default)
			)
			(layer "F.SilkS")
		)
		(fp_line
			(start -2.0574 0)
			(end -2.5146 -0.4572)
			(stroke
				(width 0.1524)
				(type default)
			)
			(layer "F.SilkS")
		)
		(fp_line
			(start -2.5146 -0.4572)
			(end -2.5146 -1.4224)
			(stroke
				(width 0.1524)
				(type default)
			)
			(layer "F.SilkS")
		)
		(fp_line
			(start -2.5146 -1.4224)
			(end 2.5146 -1.4224)
			(stroke
				(width 0.1524)
				(type default)
			)
			(layer "F.SilkS")
		)
		(fp_line
			(start 2.5146 -1.4224)
			(end 2.5146 1.4224)
			(stroke
				(width 0.1524)
				(type default)
			)
			(layer "F.SilkS")
		)
		(fp_circle
			(center -1.905 0.889)
			(end -1.905 0.635)
			(stroke
				(width 0.1524)
				(type default)
			)
			(fill no)
			(layer "F.SilkS")
		)
		(fp_poly
			(pts
				(xy -2.1844 3.5052) (xy -2.1844 2.0066) (xy -2.5146 2.0066) (xy -2.5146 -2.0066) (xy -2.1844 -2.0066)
				(xy -2.1844 -3.5052) (xy 2.1844 -3.5052) (xy 2.1844 -2.0066) (xy 2.5146 -2.0066) (xy 2.5146 2.0066)
				(xy 2.1844 2.0066) (xy 2.1844 3.5052)
			)
			(stroke
				(width 0)
				(type default)
			)
			(fill no)
			(layer "F.CrtYd")
		)
		(pad "1" smd rect
			(at -1.905 2.6416 270)
			(size 0.5588 1.7272)
			(layers "F.Cu" "F.Mask" "F.Paste")
			(net "N21700941")
		)
		(pad "2" smd rect
			(at -0.635 2.6416 270)
			(size 0.5588 1.7272)
			(layers "F.Cu" "F.Mask" "F.Paste")
			(net "N21698939")
		)
		(pad "3" smd rect
			(at 0.635 2.6416 270)
			(size 0.5588 1.7272)
			(layers "F.Cu" "F.Mask" "F.Paste")
			(net "N21698906")
		)
		(pad "4" smd rect
			(at 1.905 2.6416 270)
			(size 0.5588 1.7272)
			(layers "F.Cu" "F.Mask" "F.Paste")
			(net "GND")
		)
		(pad "5" smd rect
			(at 1.905 -2.6416 270)
			(size 0.5588 1.7272)
			(layers "F.Cu" "F.Mask" "F.Paste")
			(net "I2C_COM3_SDA")
		)
		(pad "6" smd rect
			(at 0.635 -2.6416 270)
			(size 0.5588 1.7272)
			(layers "F.Cu" "F.Mask" "F.Paste")
			(net "I2C_COM3_SCL")
		)
		(pad "7" smd rect
			(at -0.635 -2.6416 270)
			(size 0.5588 1.7272)
			(layers "F.Cu" "F.Mask" "F.Paste")
			(net "N21700943")
		)
		(pad "8" smd rect
			(at -1.905 -2.6416 270)
			(size 0.5588 1.7272)
			(layers "F.Cu" "F.Mask" "F.Paste")
			(net "P3V3_NODE1")
		)
	)
	(footprint ""
		(layer "F.Cu")
		(at 110.799626 -142.419832 90)
		(property "Reference" "PR57"
			(at 1.927352 0.092964 90)
			(unlocked yes)
			(layer "F.SilkS")
			(effects
				(font
					(size 0.635 0.4064)
					(thickness 0.1524)
				)
				(justify left)
			)
		)
		(property "Value" ""
			(at 0 0 90)
			(layer "F.Fab")
			(effects
				(font
					(size 1.27 1.27)
				)
			)
		)
		(duplicate_pad_numbers_are_jumpers no)
		(fp_line
			(start 0.7874 -0.4064)
			(end 0.7874 0.4064)
			(stroke
				(width 0.1524)
				(type default)
			)
			(layer "F.SilkS")
		)
		(fp_line
			(start -0.7874 -0.4064)
			(end 0.7874 -0.4064)
			(stroke
				(width 0.1524)
				(type default)
			)
			(layer "F.SilkS")
		)
		(fp_line
			(start 0.7874 0.4064)
			(end -0.7874 0.4064)
			(stroke
				(width 0.1524)
				(type default)
			)
			(layer "F.SilkS")
		)
		(fp_line
			(start -0.7874 0.4064)
			(end -0.7874 -0.4064)
			(stroke
				(width 0.1524)
				(type default)
			)
			(layer "F.SilkS")
		)
		(fp_poly
			(pts
				(xy -0.508 0.2794) (xy -0.508 0.2286) (xy -0.635 0.2286) (xy -0.635 -0.254) (xy -0.5334 -0.254)
				(xy -0.5334 -0.2794) (xy 0.5334 -0.2794) (xy 0.5334 -0.254) (xy 0.635 -0.254) (xy 0.635 0.254) (xy 0.5334 0.254)
				(xy 0.5334 0.2794)
			)
			(stroke
				(width 0)
				(type default)
			)
			(fill no)
			(layer "F.CrtYd")
		)
		(pad "1" smd rect
			(at 0.40005 0 90)
			(size 0.4572 0.508)
			(layers "F.Cu" "F.Mask" "F.Paste")
			(net "VR_PVCCP_NODE1_VCC")
		)
		(pad "2" smd rect
			(at -0.40005 0 90)
			(size 0.4572 0.508)
			(layers "F.Cu" "F.Mask" "F.Paste")
			(net "VR_PVCCP_NODE1_SETINI")
		)
	)
	(footprint ""
		(layer "F.Cu")
		(at 123.00712 -50.035714 90)
		(property "Reference" "R617"
			(at -1.527556 -1.042162 90)
			(unlocked yes)
			(layer "F.SilkS")
			(effects
				(font
					(size 0.7874 0.5842)
					(thickness 0.1524)
				)
				(justify left)
			)
		)
		(property "Value" ""
			(at 0 0 90)
			(layer "F.Fab")
			(effects
				(font
					(size 1.27 1.27)
				)
			)
		)
		(duplicate_pad_numbers_are_jumpers no)
		(fp_line
			(start 0.7874 -0.4064)
			(end 0.7874 0.4064)
			(stroke
				(width 0.1524)
				(type default)
			)
			(layer "F.SilkS")
		)
		(fp_line
			(start -0.7874 -0.4064)
			(end 0.7874 -0.4064)
			(stroke
				(width 0.1524)
				(type default)
			)
			(layer "F.SilkS")
		)
		(fp_line
			(start 0.7874 0.4064)
			(end -0.7874 0.4064)
			(stroke
				(width 0.1524)
				(type default)
			)
			(layer "F.SilkS")
		)
		(fp_line
			(start -0.7874 0.4064)
			(end -0.7874 -0.4064)
			(stroke
				(width 0.1524)
				(type default)
			)
			(layer "F.SilkS")
		)
		(fp_poly
			(pts
				(xy -0.508 0.2794) (xy -0.508 0.2286) (xy -0.635 0.2286) (xy -0.635 -0.254) (xy -0.5334 -0.254)
				(xy -0.5334 -0.2794) (xy 0.5334 -0.2794) (xy 0.5334 -0.254) (xy 0.635 -0.254) (xy 0.635 0.254) (xy 0.5334 0.254)
				(xy 0.5334 0.2794)
			)
			(stroke
				(width 0)
				(type default)
			)
			(fill no)
			(layer "F.CrtYd")
		)
		(pad "1" smd rect
			(at 0.40005 0 90)
			(size 0.4572 0.508)
			(layers "F.Cu" "F.Mask" "F.Paste")
			(net "P3V3_NODE1")
		)
		(pad "2" smd rect
			(at -0.40005 0 90)
			(size 0.4572 0.508)
			(layers "F.Cu" "F.Mask" "F.Paste")
			(net "SIO_PIN38")
		)
	)
	(footprint ""
		(layer "F.Cu")
		(at 136.38657 -26.569416 90)
		(property "Reference" "C485"
			(at -5.325618 0.26543 90)
			(unlocked yes)
			(layer "F.SilkS")
			(effects
				(font
					(size 0.7874 0.5842)
					(thickness 0.1524)
				)
				(justify left)
			)
		)
		(property "Value" ""
			(at 0 0 90)
			(layer "F.Fab")
			(effects
				(font
					(size 1.27 1.27)
				)
			)
		)
		(duplicate_pad_numbers_are_jumpers no)
		(fp_line
			(start 0.7874 -0.4064)
			(end 0.7874 0.4064)
			(stroke
				(width 0.1524)
				(type default)
			)
			(layer "F.SilkS")
		)
		(fp_line
			(start -0.7874 -0.4064)
			(end 0.7874 -0.4064)
			(stroke
				(width 0.1524)
				(type default)
			)
			(layer "F.SilkS")
		)
		(fp_line
			(start 0 0.381)
			(end 0 -0.381)
			(stroke
				(width 0.1524)
				(type default)
			)
			(layer "F.SilkS")
		)
		(fp_line
			(start 0.7874 0.4064)
			(end -0.7874 0.4064)
			(stroke
				(width 0.1524)
				(type default)
			)
			(layer "F.SilkS")
		)
		(fp_line
			(start -0.7874 0.4064)
			(end -0.7874 -0.4064)
			(stroke
				(width 0.1524)
				(type default)
			)
			(layer "F.SilkS")
		)
		(fp_poly
			(pts
				(xy -0.5334 0.254) (xy -0.635 0.254) (xy -0.635 0.2286) (xy -0.635 -0.254) (xy -0.5334 -0.254) (xy -0.5334 -0.2794)
				(xy 0.5334 -0.2794) (xy 0.5334 -0.254) (xy 0.635 -0.254) (xy 0.635 0.254) (xy 0.5334 0.254) (xy 0.5334 0.2794)
				(xy -0.508 0.2794) (xy -0.5334 0.2794)
			)
			(stroke
				(width 0)
				(type default)
			)
			(fill no)
			(layer "F.CrtYd")
		)
		(pad "1" smd rect
			(at 0.40005 0 90)
			(size 0.4572 0.508)
			(layers "F.Cu" "F.Mask" "F.Paste")
			(net "SIO_VREF")
		)
		(pad "2" smd rect
			(at -0.40005 0 90)
			(size 0.4572 0.508)
			(layers "F.Cu" "F.Mask" "F.Paste")
			(net "GNDA")
		)
	)
	(footprint ""
		(layer "F.Cu")
		(at 72.159114 -182.186326 180)
		(property "Reference" "R1074"
			(at 4.849368 0.458978 0)
			(unlocked yes)
			(layer "F.SilkS")
			(effects
				(font
					(size 0.7874 0.5842)
					(thickness 0.1524)
				)
				(justify left)
			)
		)
		(property "Value" ""
			(at 0 0 180)
			(layer "F.Fab")
			(effects
				(font
					(size 1.27 1.27)
				)
			)
		)
		(duplicate_pad_numbers_are_jumpers no)
		(fp_line
			(start 0.7874 0.4064)
			(end -0.7874 0.4064)
			(stroke
				(width 0.1524)
				(type default)
			)
			(layer "F.SilkS")
		)
		(fp_line
			(start 0.7874 -0.4064)
			(end 0.7874 0.4064)
			(stroke
				(width 0.1524)
				(type default)
			)
			(layer "F.SilkS")
		)
		(fp_line
			(start -0.7874 0.4064)
			(end -0.7874 -0.4064)
			(stroke
				(width 0.1524)
				(type default)
			)
			(layer "F.SilkS")
		)
		(fp_line
			(start -0.7874 -0.4064)
			(end 0.7874 -0.4064)
			(stroke
				(width 0.1524)
				(type default)
			)
			(layer "F.SilkS")
		)
		(fp_poly
			(pts
				(xy -0.508 0.2794) (xy -0.508 0.2286) (xy -0.635 0.2286) (xy -0.635 -0.254) (xy -0.5334 -0.254)
				(xy -0.5334 -0.2794) (xy 0.5334 -0.2794) (xy 0.5334 -0.254) (xy 0.635 -0.254) (xy 0.635 0.254) (xy 0.5334 0.254)
				(xy 0.5334 0.2794)
			)
			(stroke
				(width 0)
				(type default)
			)
			(fill no)
			(layer "F.CrtYd")
		)
		(pad "1" smd rect
			(at 0.40005 0 180)
			(size 0.4572 0.508)
			(layers "F.Cu" "F.Mask" "F.Paste")
			(net "GND")
		)
		(pad "2" smd rect
			(at -0.40005 0 180)
			(size 0.4572 0.508)
			(layers "F.Cu" "F.Mask" "F.Paste")
			(net "JTAG_CPLD2_TCK")
		)
	)
	(footprint ""
		(layer "F.Cu")
		(at 116.529104 -63.422784 180)
		(property "Reference" "R223"
			(at -0.95123 -0.010414 0)
			(unlocked yes)
			(layer "F.SilkS")
			(effects
				(font
					(size 0.7874 0.5842)
					(thickness 0.1524)
				)
				(justify left)
			)
		)
		(property "Value" ""
			(at 0 0 180)
			(layer "F.Fab")
			(effects
				(font
					(size 1.27 1.27)
				)
			)
		)
		(duplicate_pad_numbers_are_jumpers no)
		(fp_line
			(start 0.7874 0.4064)
			(end -0.7874 0.4064)
			(stroke
				(width 0.1524)
				(type default)
			)
			(layer "F.SilkS")
		)
		(fp_line
			(start 0.7874 -0.4064)
			(end 0.7874 0.4064)
			(stroke
				(width 0.1524)
				(type default)
			)
			(layer "F.SilkS")
		)
		(fp_line
			(start -0.7874 0.4064)
			(end -0.7874 -0.4064)
			(stroke
				(width 0.1524)
				(type default)
			)
			(layer "F.SilkS")
		)
		(fp_line
			(start -0.7874 -0.4064)
			(end 0.7874 -0.4064)
			(stroke
				(width 0.1524)
				(type default)
			)
			(layer "F.SilkS")
		)
		(fp_poly
			(pts
				(xy -0.508 0.2794) (xy -0.508 0.2286) (xy -0.635 0.2286) (xy -0.635 -0.254) (xy -0.5334 -0.254)
				(xy -0.5334 -0.2794) (xy 0.5334 -0.2794) (xy 0.5334 -0.254) (xy 0.635 -0.254) (xy 0.635 0.254) (xy 0.5334 0.254)
				(xy 0.5334 0.2794)
			)
			(stroke
				(width 0)
				(type default)
			)
			(fill no)
			(layer "F.CrtYd")
		)
		(pad "1" smd rect
			(at 0.40005 0 180)
			(size 0.4572 0.508)
			(layers "F.Cu" "F.Mask" "F.Paste")
			(net "RST_NODE1_CPU_XDP_RSTIN_L")
		)
		(pad "2" smd rect
			(at -0.40005 0 180)
			(size 0.4572 0.508)
			(layers "F.Cu" "F.Mask" "F.Paste")
			(net "P3V3_STB_NODE1")
		)
	)
	(footprint ""
		(layer "F.Cu")
		(at 70.1548 -102.413562 180)
		(property "Reference" "C826"
			(at 1.169416 3.161792 0)
			(unlocked yes)
			(layer "F.SilkS")
			(effects
				(font
					(size 0.7874 0.5842)
					(thickness 0.1524)
				)
				(justify left)
			)
		)
		(property "Value" ""
			(at 0 0 180)
			(layer "F.Fab")
			(effects
				(font
					(size 1.27 1.27)
				)
			)
		)
		(duplicate_pad_numbers_are_jumpers no)
		(fp_line
			(start 0.7874 0.4064)
			(end -0.7874 0.4064)
			(stroke
				(width 0.1524)
				(type default)
			)
			(layer "F.SilkS")
		)
		(fp_line
			(start 0.7874 -0.4064)
			(end 0.7874 0.4064)
			(stroke
				(width 0.1524)
				(type default)
			)
			(layer "F.SilkS")
		)
		(fp_line
			(start 0 0.381)
			(end 0 -0.381)
			(stroke
				(width 0.1524)
				(type default)
			)
			(layer "F.SilkS")
		)
		(fp_line
			(start -0.7874 0.4064)
			(end -0.7874 -0.4064)
			(stroke
				(width 0.1524)
				(type default)
			)
			(layer "F.SilkS")
		)
		(fp_line
			(start -0.7874 -0.4064)
			(end 0.7874 -0.4064)
			(stroke
				(width 0.1524)
				(type default)
			)
			(layer "F.SilkS")
		)
		(fp_poly
			(pts
				(xy -0.5334 0.254) (xy -0.635 0.254) (xy -0.635 0.2286) (xy -0.635 -0.254) (xy -0.5334 -0.254) (xy -0.5334 -0.2794)
				(xy 0.5334 -0.2794) (xy 0.5334 -0.254) (xy 0.635 -0.254) (xy 0.635 0.254) (xy 0.5334 0.254) (xy 0.5334 0.2794)
				(xy -0.508 0.2794) (xy -0.5334 0.2794)
			)
			(stroke
				(width 0)
				(type default)
			)
			(fill no)
			(layer "F.CrtYd")
		)
		(pad "1" smd rect
			(at 0.40005 0 180)
			(size 0.4572 0.508)
			(layers "F.Cu" "F.Mask" "F.Paste")
			(net "FM_CPLD_NODE1_P1V8_SUS_EN")
		)
		(pad "2" smd rect
			(at -0.40005 0 180)
			(size 0.4572 0.508)
			(layers "F.Cu" "F.Mask" "F.Paste")
			(net "GND")
		)
	)
	(footprint ""
		(layer "F.Cu")
		(at 183.485282 -130.602228 -90)
		(property "Reference" "R1121"
			(at 1.053338 -14.029436 90)
			(unlocked yes)
			(layer "F.SilkS")
			(effects
				(font
					(size 0.7874 0.5842)
					(thickness 0.1524)
				)
				(justify left)
			)
		)
		(property "Value" ""
			(at 0 0 270)
			(layer "F.Fab")
			(effects
				(font
					(size 1.27 1.27)
				)
			)
		)
		(duplicate_pad_numbers_are_jumpers no)
		(fp_line
			(start -0.7874 0.4064)
			(end -0.7874 -0.4064)
			(stroke
				(width 0.1524)
				(type default)
			)
			(layer "F.SilkS")
		)
		(fp_line
			(start 0.7874 0.4064)
			(end -0.7874 0.4064)
			(stroke
				(width 0.1524)
				(type default)
			)
			(layer "F.SilkS")
		)
		(fp_line
			(start -0.7874 -0.4064)
			(end 0.7874 -0.4064)
			(stroke
				(width 0.1524)
				(type default)
			)
			(layer "F.SilkS")
		)
		(fp_line
			(start 0.7874 -0.4064)
			(end 0.7874 0.4064)
			(stroke
				(width 0.1524)
				(type default)
			)
			(layer "F.SilkS")
		)
		(fp_poly
			(pts
				(xy -0.508 0.2794) (xy -0.508 0.2286) (xy -0.635 0.2286) (xy -0.635 -0.254) (xy -0.5334 -0.254)
				(xy -0.5334 -0.2794) (xy 0.5334 -0.2794) (xy 0.5334 -0.254) (xy 0.635 -0.254) (xy 0.635 0.254) (xy 0.5334 0.254)
				(xy 0.5334 0.2794)
			)
			(stroke
				(width 0)
				(type default)
			)
			(fill no)
			(layer "F.CrtYd")
		)
		(pad "1" smd rect
			(at 0.40005 0 270)
			(size 0.4572 0.508)
			(layers "F.Cu" "F.Mask" "F.Paste")
			(net "SYS_AUTO_POWER_ON_N")
		)
		(pad "2" smd rect
			(at -0.40005 0 270)
			(size 0.4572 0.508)
			(layers "F.Cu" "F.Mask" "F.Paste")
			(net "P3V3_STB_NODE1")
		)
	)
	(footprint ""
		(layer "F.Cu")
		(at 157.065472 -105.98277 -90)
		(property "Reference" "R274"
			(at -1.588262 -0.00381 90)
			(unlocked yes)
			(layer "F.SilkS")
			(effects
				(font
					(size 0.7874 0.5842)
					(thickness 0.1524)
				)
				(justify left)
			)
		)
		(property "Value" ""
			(at 0 0 270)
			(layer "F.Fab")
			(effects
				(font
					(size 1.27 1.27)
				)
			)
		)
		(duplicate_pad_numbers_are_jumpers no)
		(fp_line
			(start -0.7874 0.4064)
			(end -0.7874 -0.4064)
			(stroke
				(width 0.1524)
				(type default)
			)
			(layer "F.SilkS")
		)
		(fp_line
			(start 0.7874 0.4064)
			(end -0.7874 0.4064)
			(stroke
				(width 0.1524)
				(type default)
			)
			(layer "F.SilkS")
		)
		(fp_line
			(start -0.7874 -0.4064)
			(end 0.7874 -0.4064)
			(stroke
				(width 0.1524)
				(type default)
			)
			(layer "F.SilkS")
		)
		(fp_line
			(start 0.7874 -0.4064)
			(end 0.7874 0.4064)
			(stroke
				(width 0.1524)
				(type default)
			)
			(layer "F.SilkS")
		)
		(fp_poly
			(pts
				(xy -0.508 0.2794) (xy -0.508 0.2286) (xy -0.635 0.2286) (xy -0.635 -0.254) (xy -0.5334 -0.254)
				(xy -0.5334 -0.2794) (xy 0.5334 -0.2794) (xy 0.5334 -0.254) (xy 0.635 -0.254) (xy 0.635 0.254) (xy 0.5334 0.254)
				(xy 0.5334 0.2794)
			)
			(stroke
				(width 0)
				(type default)
			)
			(fill no)
			(layer "F.CrtYd")
		)
		(pad "1" smd rect
			(at 0.40005 0 270)
			(size 0.4572 0.508)
			(layers "F.Cu" "F.Mask" "F.Paste")
			(net "FM_CPLD_NODE1_USB_PERST_L")
		)
		(pad "2" smd rect
			(at -0.40005 0 270)
			(size 0.4572 0.508)
			(layers "F.Cu" "F.Mask" "F.Paste")
			(net "N34379705")
		)
	)
)
